# BASEBOARD_FAB2 (Tioga Pass) — schematic netlist excerpt (pin names and nets, part order shuffled) for the footprints in the layout excerpt that follows; sources: Cadence DE-HDL packaged netlist, KiCad conversion of Wiwynn_Tioga_Pass_MB.brd

CR1L4  DIODE  1N4148W IC  pkg SM  page 168 : C = FM_DB_UART_SEL4_N ; A = FM_DB_UART_SEL3_N
R9P7  RES  100.0K 1% CHIP  pkg 0402  page 200 : A = P12V_STBY ; B = A_P12V_STBY_ADR_TRIGGER
C8T6  CAP_A  47UF 4V 20% X5R  pkg 0603V  page 225 : A = PVDDQ_GHJ ; B = GND

(kicad_pcb
	(version 20260206)
	(generator "pcbnew")
	(generator_version "10.0")
	(general
		(thickness 1.6)
		(legacy_teardrops no)
	)
	(paper "A4")
	(title_block
		(title "Wiwynn_Tioga_Pass_MB.brd")
		(comment 1 "Tioga Pass / footprints 2449-2451 of 4770")
	)
	(layers
		(0 "F.Cu" signal "TOP")
		(4 "In1.Cu" signal "L2GND")
		(6 "In2.Cu" signal "L3")
		(8 "In3.Cu" signal "L4GND")
		(10 "In4.Cu" signal "L5")
		(12 "In5.Cu" signal "L6GND")
		(14 "In6.Cu" signal "L7VCC")
		(16 "In7.Cu" signal "L8VCC")
		(18 "In8.Cu" signal "L9GND")
		(20 "In9.Cu" signal "L10")
		(22 "In10.Cu" signal "L11GND")
		(24 "In11.Cu" signal "L12")
		(26 "In12.Cu" signal "L13GND")
		(2 "B.Cu" signal "BOTTOM")
		(9 "F.Adhes" user "F.Adhesive")
		(11 "B.Adhes" user "B.Adhesive")
		(13 "F.Paste" user "Package Geometry/Pastemask Top")
		(15 "B.Paste" user "Package Geometry/Pastemask Bottom")
		(5 "F.SilkS" user "Ref Des/Silkscreen Top")
		(7 "B.SilkS" user "Ref Des/Silkscreen Bottom")
		(1 "F.Mask" user "Board Geometry/Soldermask Top")
		(3 "B.Mask" user "Board Geometry/Soldermask Bottom")
		(17 "Dwgs.User" user "User.Drawings")
		(19 "Cmts.User" user "User.Comments")
		(21 "Eco1.User" user "User.Eco1")
		(23 "Eco2.User" user "User.Eco2")
		(25 "Edge.Cuts" user "Board Geometry/Outline")
		(27 "Margin" user)
		(31 "F.CrtYd" user "Package Geometry/Place Bound Top")
		(29 "B.CrtYd" user "Package Geometry/Place Bound Bottom")
		(35 "F.Fab" user "Ref Des/Assembly Top")
		(33 "B.Fab" user "Ref Des/Assembly Bottom")
	)
	(footprint ""
		(layer "B.Cu")
		(at 101.3968 -17.7546 90)
		(property "Reference" "C8T6"
			(at -1.848866 0.752348 90)
			(unlocked yes)
			(layer "B.SilkS")
			(effects
				(font
					(size 1.27 0.9652)
					(thickness 0.1524)
				)
				(justify mirror)
			)
		)
		(property "Value" ""
			(at 0 0 90)
			(layer "B.Fab")
			(effects
				(font
					(size 1.27 1.27)
				)
				(justify mirror)
			)
		)
		(duplicate_pad_numbers_are_jumpers no)
		(fp_rect
			(start 0.500126 1.598422)
			(end -0.500126 -0.201422)
			(stroke
				(width 0)
				(type default)
			)
			(fill no)
			(layer "B.CrtYd")
		)
		(fp_line
			(start 0.500126 -0.201422)
			(end -0.500126 -0.201422)
			(stroke
				(width 0.1)
				(type default)
			)
			(layer "B.Fab")
		)
		(fp_line
			(start -0.500126 -0.201422)
			(end -0.500126 1.598422)
			(stroke
				(width 0.1)
				(type default)
			)
			(layer "B.Fab")
		)
		(fp_line
			(start 0.500126 1.598422)
			(end 0.500126 -0.201422)
			(stroke
				(width 0.1)
				(type default)
			)
			(layer "B.Fab")
		)
		(fp_line
			(start -0.500126 1.598422)
			(end 0.500126 1.598422)
			(stroke
				(width 0.1)
				(type default)
			)
			(layer "B.Fab")
		)
		(pad "1" smd rect
			(at 0 0)
			(size 0.889 0.9906)
			(layers "B.Cu" "B.Mask" "B.Paste")
			(net "PVDDQ_GHJ")
		)
		(pad "2" smd rect
			(at 0 1.397)
			(size 0.889 0.9906)
			(layers "B.Cu" "B.Mask" "B.Paste")
			(net "GND")
		)
		(zone
			(layer "B.Cu")
			(hatch none 0.5)
			(connect_pads
				(clearance 0)
			)
			(min_thickness 0.25)
			(keepout
				(tracks not_allowed)
				(vias allowed)
				(pads allowed)
				(copperpour not_allowed)
				(footprints allowed)
			)
			(placement
				(enabled no)
				(sheetname "")
			)
			(fill
				(thermal_gap 0.5)
				(thermal_bridge_width 0.5)
				(island_removal_mode 0)
			)
			(polygon
				(pts
					(xy 102.3493 -18.2499) (xy 101.8413 -18.2499) (xy 101.8413 -17.2593) (xy 102.3493 -17.2593)
				)
			)
		)
		(zone
			(layer "B.Cu")
			(hatch none 0.5)
			(connect_pads
				(clearance 0)
			)
			(min_thickness 0.25)
			(keepout
				(tracks allowed)
				(vias not_allowed)
				(pads allowed)
				(copperpour not_allowed)
				(footprints allowed)
			)
			(placement
				(enabled no)
				(sheetname "")
			)
			(fill
				(thermal_gap 0.5)
				(thermal_bridge_width 0.5)
				(island_removal_mode 0)
			)
			(polygon
				(pts
					(xy 102.3493 -18.2499) (xy 101.8413 -18.2499) (xy 101.8413 -17.2593) (xy 102.3493 -17.2593)
				)
			)
		)
	)
	(footprint ""
		(layer "B.Cu")
		(at 484.124 -143.4084 90)
		(property "Reference" "CR1L4"
			(at 0 0 90)
			(layer "B.SilkS")
			(hide yes)
			(effects
				(font
					(size 1.27 1.27)
				)
				(justify mirror)
			)
		)
		(property "Value" ""
			(at 0 0 90)
			(layer "B.Fab")
			(effects
				(font
					(size 1.27 1.27)
				)
				(justify mirror)
			)
		)
		(duplicate_pad_numbers_are_jumpers no)
		(fp_line
			(start 0.9144 0.1016)
			(end 0.9144 2.9464)
			(stroke
				(width 0.1524)
				(type default)
			)
			(layer "B.SilkS")
		)
		(fp_line
			(start 0.8382 0.1016)
			(end 0.9144 0.1016)
			(stroke
				(width 0.1524)
				(type default)
			)
			(layer "B.SilkS")
		)
		(fp_line
			(start -0.8382 0.1016)
			(end -0.9144 0.1016)
			(stroke
				(width 0.1524)
				(type default)
			)
			(layer "B.SilkS")
		)
		(fp_line
			(start -0.9144 0.1016)
			(end -0.9144 2.9464)
			(stroke
				(width 0.1524)
				(type default)
			)
			(layer "B.SilkS")
		)
		(fp_line
			(start 0.9144 2.9464)
			(end 0.8382 2.9464)
			(stroke
				(width 0.1524)
				(type default)
			)
			(layer "B.SilkS")
		)
		(fp_line
			(start -0.9144 2.9464)
			(end -0.8382 2.9464)
			(stroke
				(width 0.1524)
				(type default)
			)
			(layer "B.SilkS")
		)
		(fp_circle
			(center -1.128776 -0.907288)
			(end -1.128776 -0.780288)
			(stroke
				(width 0.254)
				(type default)
			)
			(fill no)
			(layer "B.SilkS")
		)
		(fp_poly
			(pts
				(xy 0 0.1016) (xy -0.5334 0.1016) (xy -0.7366 0.1016) (xy -0.9144 0.1016) (xy -0.9144 2.9464) (xy -0.8382 2.9464)
				(xy -0.762 2.9464) (xy 0.9144 2.9464) (xy 0.9144 2.7686) (xy 0.9144 2.159) (xy 0.9144 0.1016) (xy 0.7366 0.1016)
				(xy 0.5842 0.1016)
			)
			(stroke
				(width 0)
				(type default)
			)
			(fill no)
			(layer "B.CrtYd")
		)
		(fp_line
			(start 0.9144 0.1016)
			(end 0.9144 2.9464)
			(stroke
				(width 0.1)
				(type default)
			)
			(layer "B.Fab")
		)
		(fp_line
			(start -0.9144 0.1016)
			(end 0.9144 0.1016)
			(stroke
				(width 0.1)
				(type default)
			)
			(layer "B.Fab")
		)
		(fp_line
			(start 0.9144 2.9464)
			(end -0.9144 2.9464)
			(stroke
				(width 0.1)
				(type default)
			)
			(layer "B.Fab")
		)
		(fp_line
			(start -0.9144 2.9464)
			(end -0.9144 0.1016)
			(stroke
				(width 0.1)
				(type default)
			)
			(layer "B.Fab")
		)
		(fp_circle
			(center -1.128776 -0.907288)
			(end -1.128776 -0.780288)
			(stroke
				(width 0.254)
				(type default)
			)
			(fill no)
			(layer "B.Fab")
		)
		(pad "1" smd rect
			(at 0 0)
			(size 1.524 0.762)
			(layers "B.Cu" "B.Mask" "B.Paste")
			(net "FM_DB_UART_SEL4_N")
		)
		(pad "2" smd rect
			(at 0 3.048 180)
			(size 1.524 0.762)
			(layers "B.Cu" "B.Mask" "B.Paste")
			(net "FM_DB_UART_SEL3_N")
		)
	)
	(footprint ""
		(layer "B.Cu")
		(at 18.5674 -84.3026 90)
		(property "Reference" "R9P7"
			(at 0 0 90)
			(layer "B.SilkS")
			(hide yes)
			(effects
				(font
					(size 1.27 1.27)
				)
				(justify mirror)
			)
		)
		(property "Value" ""
			(at 0 0 90)
			(layer "B.Fab")
			(effects
				(font
					(size 1.27 1.27)
				)
				(justify mirror)
			)
		)
		(duplicate_pad_numbers_are_jumpers no)
		(fp_poly
			(pts
				(xy 0.2794 -0.1016) (xy -0.2794 -0.1016) (xy -0.2794 0.9906) (xy 0.2794 0.9906)
			)
			(stroke
				(width 0)
				(type default)
			)
			(fill no)
			(layer "B.CrtYd")
		)
		(fp_line
			(start 0.2794 -0.1016)
			(end 0.2794 0.9906)
			(stroke
				(width 0.1)
				(type default)
			)
			(layer "B.Fab")
		)
		(fp_line
			(start -0.2794 -0.1016)
			(end 0.2794 -0.1016)
			(stroke
				(width 0.1)
				(type default)
			)
			(layer "B.Fab")
		)
		(fp_line
			(start 0.2794 0.9906)
			(end -0.2794 0.9906)
			(stroke
				(width 0.1)
				(type default)
			)
			(layer "B.Fab")
		)
		(fp_line
			(start -0.2794 0.9906)
			(end -0.2794 -0.1016)
			(stroke
				(width 0.1)
				(type default)
			)
			(layer "B.Fab")
		)
		(pad "1" smd rect
			(at 0 0 270)
			(size 0.508 0.508)
			(layers "B.Cu" "B.Mask" "B.Paste")
			(net "P12V_STBY")
		)
		(pad "2" smd rect
			(at 0 0.889 270)
			(size 0.508 0.508)
			(layers "B.Cu" "B.Mask" "B.Paste")
			(net "A_P12V_STBY_ADR_TRIGGER")
		)
		(zone
			(layer "B.Cu")
			(hatch none 0.5)
			(connect_pads
				(clearance 0)
			)
			(min_thickness 0.25)
			(keepout
				(tracks allowed)
				(vias not_allowed)
				(pads allowed)
				(copperpour not_allowed)
				(footprints allowed)
			)
			(placement
				(enabled no)
				(sheetname "")
			)
			(fill
				(thermal_gap 0.5)
				(thermal_bridge_width 0.5)
				(island_removal_mode 0)
			)
			(polygon
				(pts
					(xy 18.8214 -84.5566) (xy 18.8214 -84.0486) (xy 19.2024 -84.0486) (xy 19.2024 -84.5566)
				)
			)
		)
		(zone
			(layer "B.Cu")
			(hatch none 0.5)
			(connect_pads
				(clearance 0)
			)
			(min_thickness 0.25)
			(keepout
				(tracks not_allowed)
				(vias allowed)
				(pads allowed)
				(copperpour not_allowed)
				(footprints allowed)
			)
			(placement
				(enabled no)
				(sheetname "")
			)
			(fill
				(thermal_gap 0.5)
				(thermal_bridge_width 0.5)
				(island_removal_mode 0)
			)
			(polygon
				(pts
					(xy 19.2024 -84.5566) (xy 19.2024 -84.0486) (xy 18.8214 -84.0486) (xy 18.8214 -84.5566)
				)
			)
		)
	)
)
